# S9S_MB_2U (Grand Teton) — schematic netlist excerpt (pin names and nets, part order shuffled) for the footprints in the layout excerpt that follows; sources: Cadence DE-HDL packaged netlist, KiCad conversion of 03242023_DA0F0TMBIJ0_F0T_Motherboard_J_brd_V01_OCP.brd

PC498_P1_7  Q_CAP  22UF 4V 20% X6S  pkg C0805  page 288 : A = PVCCIN_CPU1 ; B = GND
R61  Q_RES  10 1% CHIP  pkg 0402LF  page 44 : A = H_CPU_PRDY_QS_GTL_N ; B = H_CPU1_PRDY_QS_GTL_R_N
C155  Q_CAP_DIFFBUS  DIFF BUS_0.22UF 6.3V 20% X6S  pkg C0201  page 178 : \1\ = DMI_CPU0_PCH_RX_C_DN<7> ; \2\ = DMI_CPU0_PCH_RX_DN<7>
C1436  Q_CAP  0.22UF 6.3V 10% X6S  pkg C0201  page 75 : A = PVPP_HBM_CPU0 ; B = GND

(kicad_pcb
	(version 20260206)
	(generator "pcbnew")
	(generator_version "10.0")
	(general
		(thickness 1.6)
		(legacy_teardrops no)
	)
	(paper "A4")
	(title_block
		(title "03242023_DA0F0TMBIJ0_F0T_Motherboard_J_brd_V01_OCP.brd")
		(comment 1 "Grand Teton / footprints 5620-5623 of 6105")
	)
	(layers
		(0 "F.Cu" signal "TOP")
		(4 "In1.Cu" signal "GND")
		(6 "In2.Cu" signal "IN1")
		(8 "In3.Cu" signal "GND1")
		(10 "In4.Cu" signal "IN2")
		(12 "In5.Cu" signal "GND2")
		(14 "In6.Cu" signal "IN3")
		(16 "In7.Cu" signal "GND3")
		(18 "In8.Cu" signal "VCC")
		(20 "In9.Cu" signal "VCC1")
		(22 "In10.Cu" signal "GND4")
		(24 "In11.Cu" signal "IN4")
		(26 "In12.Cu" signal "GND5")
		(28 "In13.Cu" signal "IN5")
		(30 "In14.Cu" signal "GND6")
		(32 "In15.Cu" signal "IN6")
		(34 "In16.Cu" signal "GND7")
		(2 "B.Cu" signal "BOTTOM")
		(9 "F.Adhes" user "F.Adhesive")
		(11 "B.Adhes" user "B.Adhesive")
		(13 "F.Paste" user "Package Geometry/Pastemask Top")
		(15 "B.Paste" user "Package Geometry/Pastemask Bottom")
		(5 "F.SilkS" user "Ref Des/Silkscreen Top")
		(7 "B.SilkS" user "Ref Des/Silkscreen Bottom")
		(1 "F.Mask" user "Board Geometry/Soldermask Top")
		(3 "B.Mask" user "Board Geometry/Soldermask Bottom")
		(17 "Dwgs.User" user "User.Drawings")
		(19 "Cmts.User" user "User.Comments")
		(21 "Eco1.User" user "User.Eco1")
		(23 "Eco2.User" user "User.Eco2")
		(25 "Edge.Cuts" user "Board Geometry/Outline")
		(27 "Margin" user)
		(31 "F.CrtYd" user "Package Geometry/Place Bound Top")
		(29 "B.CrtYd" user "Package Geometry/Place Bound Bottom")
		(35 "F.Fab" user "Ref Des/Assembly Top")
		(33 "B.Fab" user "Ref Des/Assembly Bottom")
	)
	(footprint ""
		(layer "B.Cu")
		(at 79.836772 -331.596492 -90)
		(property "Reference" "PC498_P1_7"
			(at 0 0 90)
			(layer "B.SilkS")
			(hide yes)
			(effects
				(font
					(size 1.27 1.27)
				)
				(justify mirror)
			)
		)
		(property "Value" ""
			(at 0 0 90)
			(layer "B.Fab")
			(effects
				(font
					(size 1.27 1.27)
				)
				(justify mirror)
			)
		)
		(duplicate_pad_numbers_are_jumpers no)
		(fp_line
			(start -1.524 0.762)
			(end 1.524 0.762)
			(stroke
				(width 0.1524)
				(type default)
			)
			(layer "B.SilkS")
		)
		(fp_line
			(start 1.524 0.762)
			(end 1.524 -0.762)
			(stroke
				(width 0.1524)
				(type default)
			)
			(layer "B.SilkS")
		)
		(fp_line
			(start -1.524 -0.762)
			(end -1.524 0.762)
			(stroke
				(width 0.1524)
				(type default)
			)
			(layer "B.SilkS")
		)
		(fp_line
			(start 1.524 -0.762)
			(end -1.524 -0.762)
			(stroke
				(width 0.1524)
				(type default)
			)
			(layer "B.SilkS")
		)
		(fp_line
			(start -1.1049 0.724916)
			(end -1.1049 -0.724916)
			(stroke
				(width 0.1)
				(type default)
			)
			(layer "B.Fab")
		)
		(fp_line
			(start 1.1049 0.724916)
			(end -1.1049 0.724916)
			(stroke
				(width 0.1)
				(type default)
			)
			(layer "B.Fab")
		)
		(fp_line
			(start -1.1049 -0.724916)
			(end 1.1049 -0.724916)
			(stroke
				(width 0.1)
				(type default)
			)
			(layer "B.Fab")
		)
		(fp_line
			(start 1.1049 -0.724916)
			(end 1.1049 0.724916)
			(stroke
				(width 0.1)
				(type default)
			)
			(layer "B.Fab")
		)
		(pad "1" smd rect
			(at 0.889 0 270)
			(size 1.016 1.27)
			(layers "B.Cu" "B.Mask" "B.Paste")
			(net "PVCCIN_CPU1")
		)
		(pad "2" smd rect
			(at -0.889 0 270)
			(size 1.016 1.27)
			(layers "B.Cu" "B.Mask" "B.Paste")
			(net "GND")
		)
	)
	(footprint ""
		(layer "B.Cu")
		(at 391.408158 -336.43697)
		(property "Reference" "C1436"
			(at 0 0 0)
			(layer "B.SilkS")
			(hide yes)
			(effects
				(font
					(size 1.27 1.27)
				)
				(justify mirror)
			)
		)
		(property "Value" ""
			(at 0 0 0)
			(layer "B.Fab")
			(effects
				(font
					(size 1.27 1.27)
				)
				(justify mirror)
			)
		)
		(duplicate_pad_numbers_are_jumpers no)
		(fp_line
			(start -0.299974 -0.150114)
			(end -0.299974 0.150114)
			(stroke
				(width 0.1)
				(type default)
			)
			(layer "B.Fab")
		)
		(fp_line
			(start -0.299974 0.150114)
			(end 0.299974 0.150114)
			(stroke
				(width 0.1)
				(type default)
			)
			(layer "B.Fab")
		)
		(fp_line
			(start 0.299974 -0.150114)
			(end -0.299974 -0.150114)
			(stroke
				(width 0.1)
				(type default)
			)
			(layer "B.Fab")
		)
		(fp_line
			(start 0.299974 0.150114)
			(end 0.299974 -0.150114)
			(stroke
				(width 0.1)
				(type default)
			)
			(layer "B.Fab")
		)
		(pad "1" smd rect
			(at 0.2667 0 180)
			(size 0.3048 0.381)
			(layers "B.Cu" "B.Mask" "B.Paste")
			(net "PVPP_HBM_CPU0")
		)
		(pad "2" smd rect
			(at -0.2667 0 180)
			(size 0.3048 0.381)
			(layers "B.Cu" "B.Mask" "B.Paste")
			(net "GND")
		)
	)
	(footprint ""
		(layer "B.Cu")
		(at 349.675704 -65.09512)
		(property "Reference" "C155"
			(at 0 0 0)
			(layer "B.SilkS")
			(hide yes)
			(effects
				(font
					(size 1.27 1.27)
				)
				(justify mirror)
			)
		)
		(property "Value" ""
			(at 0 0 0)
			(layer "B.Fab")
			(effects
				(font
					(size 1.27 1.27)
				)
				(justify mirror)
			)
		)
		(duplicate_pad_numbers_are_jumpers no)
		(fp_line
			(start -0.299974 -0.150114)
			(end -0.299974 0.150114)
			(stroke
				(width 0.1)
				(type default)
			)
			(layer "B.Fab")
		)
		(fp_line
			(start -0.299974 0.150114)
			(end 0.299974 0.150114)
			(stroke
				(width 0.1)
				(type default)
			)
			(layer "B.Fab")
		)
		(fp_line
			(start 0.299974 -0.150114)
			(end -0.299974 -0.150114)
			(stroke
				(width 0.1)
				(type default)
			)
			(layer "B.Fab")
		)
		(fp_line
			(start 0.299974 0.150114)
			(end 0.299974 -0.150114)
			(stroke
				(width 0.1)
				(type default)
			)
			(layer "B.Fab")
		)
		(pad "1" smd rect
			(at 0.2667 0 180)
			(size 0.3048 0.381)
			(layers "B.Cu" "B.Mask" "B.Paste")
			(net "DMI_CPU0_PCH_RX_C_DN<7>")
		)
		(pad "2" smd rect
			(at -0.2667 0 180)
			(size 0.3048 0.381)
			(layers "B.Cu" "B.Mask" "B.Paste")
			(net "DMI_CPU0_PCH_RX_DN<7>")
		)
	)
	(footprint ""
		(layer "B.Cu")
		(at 83.478624 -184.096152 -90)
		(property "Reference" "R61"
			(at 0 0 90)
			(layer "B.SilkS")
			(hide yes)
			(effects
				(font
					(size 1.27 1.27)
				)
				(justify mirror)
			)
		)
		(property "Value" ""
			(at 0 0 90)
			(layer "B.Fab")
			(effects
				(font
					(size 1.27 1.27)
				)
				(justify mirror)
			)
		)
		(duplicate_pad_numbers_are_jumpers no)
		(fp_line
			(start -0.7874 0.4064)
			(end 0.7874 0.4064)
			(stroke
				(width 0.1524)
				(type default)
			)
			(layer "B.SilkS")
		)
		(fp_line
			(start 0.7874 0.4064)
			(end 0.7874 -0.4064)
			(stroke
				(width 0.1524)
				(type default)
			)
			(layer "B.SilkS")
		)
		(fp_line
			(start -0.7874 -0.4064)
			(end -0.7874 0.4064)
			(stroke
				(width 0.1524)
				(type default)
			)
			(layer "B.SilkS")
		)
		(fp_line
			(start 0.7874 -0.4064)
			(end -0.7874 -0.4064)
			(stroke
				(width 0.1524)
				(type default)
			)
			(layer "B.SilkS")
		)
		(fp_line
			(start -0.67945 0.3048)
			(end -0.120396 0.3048)
			(stroke
				(width 0.1)
				(type default)
			)
			(layer "B.Fab")
		)
		(fp_line
			(start -0.120396 0.3048)
			(end -0.120396 0.2794)
			(stroke
				(width 0.1)
				(type default)
			)
			(layer "B.Fab")
		)
		(fp_line
			(start 0.12065 0.3048)
			(end 0.67945 0.3048)
			(stroke
				(width 0.1)
				(type default)
			)
			(layer "B.Fab")
		)
		(fp_line
			(start 0.67945 0.3048)
			(end 0.67945 -0.305054)
			(stroke
				(width 0.1)
				(type default)
			)
			(layer "B.Fab")
		)
		(fp_line
			(start -0.120396 0.2794)
			(end 0.12065 0.2794)
			(stroke
				(width 0.1)
				(type default)
			)
			(layer "B.Fab")
		)
		(fp_line
			(start 0.12065 0.2794)
			(end 0.12065 0.3048)
			(stroke
				(width 0.1)
				(type default)
			)
			(layer "B.Fab")
		)
		(fp_line
			(start -0.12065 -0.2794)
			(end -0.12065 -0.3048)
			(stroke
				(width 0.1)
				(type default)
			)
			(layer "B.Fab")
		)
		(fp_line
			(start 0.12065 -0.2794)
			(end -0.12065 -0.2794)
			(stroke
				(width 0.1)
				(type default)
			)
			(layer "B.Fab")
		)
		(fp_line
			(start -0.67945 -0.3048)
			(end -0.67945 0.3048)
			(stroke
				(width 0.1)
				(type default)
			)
			(layer "B.Fab")
		)
		(fp_line
			(start -0.12065 -0.3048)
			(end -0.67945 -0.3048)
			(stroke
				(width 0.1)
				(type default)
			)
			(layer "B.Fab")
		)
		(fp_line
			(start 0.12065 -0.305054)
			(end 0.12065 -0.2794)
			(stroke
				(width 0.1)
				(type default)
			)
			(layer "B.Fab")
		)
		(fp_line
			(start 0.67945 -0.305054)
			(end 0.12065 -0.305054)
			(stroke
				(width 0.1)
				(type default)
			)
			(layer "B.Fab")
		)
		(pad "1" smd circle
			(at 0.40005 0 90)
			(size 0 0)
			(layers "B.Cu" "B.Mask" "B.Paste")
			(net "H_CPU_PRDY_QS_GTL_N")
		)
		(pad "2" smd circle
			(at -0.40005 0 90)
			(size 0 0)
			(layers "B.Cu" "B.Mask" "B.Paste")
			(net "H_CPU1_PRDY_QS_GTL_R_N")
		)
	)
)
